# BASEBOARD_FAB2 (Tioga Pass) — schematic parts with pin connectivity, parts 2392–2398 of 4751; source: Cadence DE-HDL packaged netlist (pstxprt.dat, pstxnet.dat, pstchip.dat)

J9A2  CONN14_H54902001  CONN  pkg PIP  page 155
  1  IO1  BI  = LED_POSTCODE_0_R
  2  IO2  BI  = LED_POSTCODE_1_R
  3  IO3  BI  = LED_POSTCODE_2_R
  4  IO4  BI  = LED_POSTCODE_3_R
  5  IO5  BI  = LED_POSTCODE_4_R
  6  IO6  BI  = LED_POSTCODE_5_R
  7  IO7  BI  = LED_POSTCODE_6_R
  8  IO8  BI  = LED_POSTCODE_7_R
  9  IO9  BI  = SPA_MID_DBG1_TX
  10  IO10  BI  = SPA_5V_SIN_SW
  11  IO11  BI  = FM_DEBUG_RST_BTN_N
  12  IO12  BI  = FM_UART_SWITCH_N
  13  IO13  BI  = GND
  14  IO14  BI  = P5V_STBY_DGB_FS

J9A3  SCONN60_C21100002  CONN  pkg SMLF  page 111
  1  IO1  UNSPEC  = XDP_DEBUG_CONSENT_N
  2  IO2  UNSPEC  = GND
  3  IO3  UNSPEC  = XDP_PREQ_N
  4  IO4  UNSPEC  = TP_XDP_CPU_OBSFN_C0
  5  IO5  UNSPEC  = XDP_PRDY_N
  6  IO6  UNSPEC  = XDP_SPI_PCH_MOSI_BOOT_HALT_N
  7  IO7  UNSPEC  = GND
  8  IO8  UNSPEC  = GND
  9  IO9  UNSPEC  = TP_XDP_OBSDATA_A0
  10  IO10  UNSPEC  = TP_XDP_CPU_OBSDATA_C0
  11  IO11  UNSPEC  = TP_XDP_OBSDATA_A1
  12  IO12  UNSPEC  = TP_XDP_CPU_OBSDATA_C1
  13  IO13  UNSPEC  = GND
  14  IO14  UNSPEC  = GND
  15  IO15  UNSPEC  = TP_XDP_OBSDATA_A2
  16  IO16  UNSPEC  = TP_XDP_CPU_OBSDATA_C2
  17  IO17  UNSPEC  = TP_XDP_OBSDATA_A3
  18  IO18  UNSPEC  = TP_XDP_CPU_OBSDATA_C3
  19  IO19  UNSPEC  = GND
  20  IO20  UNSPEC  = GND
  21  IO21  UNSPEC  = TP_XDP_OBSFN_B0
  22  IO22  UNSPEC  = XDP_OBSFN_B0_MBP6_N
  23  IO23  UNSPEC  = TP_XDP_OBSFN_B1
  24  IO24  UNSPEC  = XDP_OBSFN_B1_MBP7_N
  25  IO25  UNSPEC  = GND
  26  IO26  UNSPEC  = GND
  27  IO27  UNSPEC  = TP_XDP_OBSDATA_B0
  28  IO28  UNSPEC  = TP_XDP_CPU_OBSDATA_D0
  29  IO29  UNSPEC  = TP_XDP_OBSDATA_B1
  30  IO30  UNSPEC  = TP_XDP_CPU_OBSDATA_D1
  31  IO31  UNSPEC  = GND
  32  IO32  UNSPEC  = GND
  33  IO33  UNSPEC  = TP_XDP_OBSDATA_B2
  34  IO34  UNSPEC  = TP_XDP_CPU_OBSDATA_D2
  35  IO35  UNSPEC  = TP_XDP_OBSDATA_B3
  36  IO36  UNSPEC  = TP_XDP_CPU_OBSDATA_D3
  37  IO37  UNSPEC  = GND
  38  IO38  UNSPEC  = GND
  39  IO39  UNSPEC  = XDP_RSMRST_N
  40  IO40  UNSPEC  = CLK_100M_PCH_XDP_DP
  41  IO41  UNSPEC  = XDP_PWRGD_RST_N
  42  IO42  UNSPEC  = CLK_100M_PCH_XDP_DN
  43  IO43  UNSPEC  = P1V05_PCH_STBY
  44  IO44  UNSPEC  = P1V05_PCH_STBY
  45  IO45  UNSPEC  = XDP_CPU_PWR_DEBUG_N
  46  IO46  UNSPEC  = XDP_ITP_PMODE
  47  IO47  UNSPEC  = XDP_SYSPWROK
  48  IO48  UNSPEC  = XDP_RST_CO_N
  49  IO49  UNSPEC  = GND
  50  IO50  UNSPEC  = GND
  51  IO51  UNSPEC  = SMB_HOST_STBY_LVC3_SDA
  52  IO52  UNSPEC  = XDP_TDO
  53  IO53  UNSPEC  = SMB_HOST_STBY_LVC3_SCL
  54  IO54  UNSPEC  = XDP_TRST_N
  55  IO55  UNSPEC  = XDP_PCH_TCK1
  56  IO56  UNSPEC  = XDP_TDI
  57  IO57  UNSPEC  = XDP_CPU_TCK0
  58  IO58  UNSPEC  = XDP_TMS
  59  IO59  UNSPEC  = GND
  60  IO60  UNSPEC  = XDP_PRESENT_N

J9B1  CONN9_H51826001  CONN  pkg PIP2  page 176
  1  VBUS  BI  = P5V_USB
  2  DN  BI  = USB2_P01_ESD_DN
  3  DP  BI  = USB2_P01_ESD_DP
  4  GND  GROUND  = GND
  5  STDA_SSRXN  BI  = SMB_DEBUG_STBY_LVC3_SCL_CONN
  6  STDA_SSRXP  BI  = SMB_DEBUG_STBY_LVC3_SDA_CONN
  7  GND_DRAIN  GROUND  = DEBUG_CARD2_PRSNT
  8  STDA_SSTXN  BI  = SPA_MID_DBG2_TX
  9  STDA_SSTXP  BI  = SPA_MID_DBG2_RX
  MH1  MH1  GROUND  = GND
  MH2  MH2  GROUND  = GND
  MH3  MH3  GROUND  = GND
  MH4  MH4  GROUND  = GND

J9B2  CONN3_C95678002  CONN  pkg PIP  page 156
  1  IO1  UNSPEC  = SMB_SMLINK0_STBY_LVC3_SDA
  2  IO2  UNSPEC  = GND
  3  IO3  UNSPEC  = SMB_SMLINK0_STBY_LVC3_SCL

J9B3  SCONN120_A28699018  SCONN  pkg SM  page 186
  1  IO1  BI  = FM_MEZZA_PRSNT1_N
  2  IO2  BI  = P12V_STBY
  3  IO3  BI  = P5V_STBY
  4  IO4  BI  = P12V_STBY
  5  IO5  BI  = P5V_STBY
  6  IO6  BI  = P12V_STBY
  7  IO7  BI  = P5V_STBY
  8  IO8  BI  = GND
  9  IO9  BI  = GND
  10  IO10  BI  = GND
  11  IO11  BI  = GND
  12  IO12  BI  = P3V3_STBY
  13  IO13  BI  = P3V3_STBY
  14  IO14  BI  = GND
  15  IO15  BI  = GND
  16  IO16  BI  = GND
  17  IO17  BI  = GND
  18  IO18  BI  = P3V3
  19  IO19  BI  = P3V3
  20  IO20  BI  = P3V3
  21  IO21  BI  = P3V3
  22  IO22  BI  = P3V3
  23  IO23  BI  = P3V3
  24  IO24  BI  = P3V3
  25  IO25  BI  = P3V3
  26  IO26  BI  = GND
  27  IO27  BI  = RMII_BMC_OCP_CRSDV_R
  28  IO28  BI  = IRQ_MEZZ_LAN_ALERT_N
  29  IO29  BI  = CLK_50M_CKMNG_OCP
  30  IO30  BI  = SMB_OCP_FRU_STBY_LVC3_SCL
  31  IO31  BI  = RMII_BMC_OCP_TXEN
  32  IO32  BI  = SMB_OCP_FRU_STBY_LVC3_SDA
  33  IO33  BI  = RST_PCIE_CPU_DEV0_R_N
  34  IO34  BI  = FM_PE_OCP_WAKE_N
  35  IO35  BI  = SMB_OCP_LAN_STBY_LVC3_SCL
  36  IO36  BI  = RMII_BMC_OCP_RXER_R
  37  IO37  BI  = SMB_OCP_LAN_STBY_LVC3_SDA
  38  IO38  BI  = GND
  39  IO39  BI  = GND
  40  IO40  BI  = RMII_BMC_OCP_TXD0
  41  IO41  BI  = GND
  42  IO42  BI  = RMII_BMC_OCP_TXD1
  43  IO43  BI  = RMII_BMC_OCP_RXD0_R
  44  IO44  BI  = GND
  45  IO45  BI  = RMII_BMC_OCP_RXD1_R
  46  IO46  BI  = GND
  47  IO47  BI  = GND
  48  IO48  BI  = CLK_100M_MEZZ1_DP
  49  IO49  BI  = GND
  50  IO50  BI  = CLK_100M_MEZZ1_DN
  51  IO51  BI  = CLK_100M_MEZZ2_DP
  52  IO52  BI  = GND
  53  IO53  BI  = CLK_100M_MEZZ2_DN
  54  IO54  BI  = GND
  55  IO55  BI  = GND
  56  IO56  BI  = P3E_OCP_CPU0_PE3_C_TXP<15>
  57  IO57  BI  = GND
  58  IO58  BI  = P3E_OCP_CPU0_PE3_C_TXN<15>
  59  IO59  BI  = P3E_CPU0_PE3_OCP_RXP<15>
  60  IO60  BI  = GND
  61  IO61  BI  = P3E_CPU0_PE3_OCP_RXN<15>
  62  IO62  BI  = GND
  63  IO63  BI  = GND
  64  IO64  BI  = P3E_OCP_CPU0_PE3_C_TXP<14>
  65  IO65  BI  = GND
  66  IO66  BI  = P3E_OCP_CPU0_PE3_C_TXN<14>
  67  IO67  BI  = P3E_CPU0_PE3_OCP_RXP<14>
  68  IO68  BI  = GND
  69  IO69  BI  = P3E_CPU0_PE3_OCP_RXN<14>
  70  IO70  BI  = GND
  71  IO71  BI  = GND
  72  IO72  BI  = P3E_OCP_CPU0_PE3_C_TXP<13>
  73  IO73  BI  = GND
  74  IO74  BI  = P3E_OCP_CPU0_PE3_C_TXN<13>
  75  IO75  BI  = P3E_CPU0_PE3_OCP_RXP<13>
  76  IO76  BI  = GND
  77  IO77  BI  = P3E_CPU0_PE3_OCP_RXN<13>
  78  IO78  BI  = GND
  79  IO79  BI  = GND
  80  IO80  BI  = P3E_OCP_CPU0_PE3_C_TXP<12>
  81  IO81  BI  = GND
  82  IO82  BI  = P3E_OCP_CPU0_PE3_C_TXN<12>
  83  IO83  BI  = P3E_CPU0_PE3_OCP_RXP<12>
  84  IO84  BI  = GND
  85  IO85  BI  = P3E_CPU0_PE3_OCP_RXN<12>
  86  IO86  BI  = GND
  87  IO87  BI  = GND
  88  IO88  BI  = P3E_OCP_CPU0_PE3_C_TXP<11>
  89  IO89  BI  = GND
  90  IO90  BI  = P3E_OCP_CPU0_PE3_C_TXN<11>
  91  IO91  BI  = P3E_CPU0_PE3_OCP_RXP<11>
  92  IO92  BI  = GND
  93  IO93  BI  = P3E_CPU0_PE3_OCP_RXN<11>
  94  IO94  BI  = GND
  95  IO95  BI  = GND
  96  IO96  BI  = P3E_OCP_CPU0_PE3_C_TXP<10>
  97  IO97  BI  = GND
  98  IO98  BI  = P3E_OCP_CPU0_PE3_C_TXN<10>
  99  IO99  BI  = P3E_CPU0_PE3_OCP_RXP<10>
  100  IO100  BI  = GND
  101  IO101  BI  = P3E_CPU0_PE3_OCP_RXN<10>
  102  IO102  BI  = GND
  103  IO103  BI  = GND
  104  IO104  BI  = P3E_OCP_CPU0_PE3_C_TXP<9>
  105  IO105  BI  = GND
  106  IO106  BI  = P3E_OCP_CPU0_PE3_C_TXN<9>
  107  IO107  BI  = P3E_CPU0_PE3_OCP_RXP<9>
  108  IO108  BI  = GND
  109  IO109  BI  = P3E_CPU0_PE3_OCP_RXN<9>
  110  IO110  BI  = GND
  111  IO111  BI  = GND
  112  IO112  BI  = P3E_OCP_CPU0_PE3_C_TXP<8>
  113  IO113  BI  = GND
  114  IO114  BI  = P3E_OCP_CPU0_PE3_C_TXN<8>
  115  IO115  BI  = P3E_CPU0_PE3_OCP_RXP<8>
  116  IO116  BI  = GND
  117  IO117  BI  = P3E_CPU0_PE3_OCP_RXN<8>
  118  IO118  BI  = GND
  119  IO119  BI  = GND
  120  IO120  BI  = FM_OCP_MEZZA_PRES_N

J9B4  SCONN10_C12536004  CONN  pkg SMLF  page 113
  1  IO1  UNSPEC  = JTAG_MCP_TCK_R
  2  IO2  UNSPEC  = GND
  3  IO3  UNSPEC  = JTAG_MCP_MUX_TDO
  4  IO4  UNSPEC  = P1V8_MCP_CPU0
  5  IO5  UNSPEC  = JTAG_MCP_TMS_R
  6  IO6  UNSPEC  = JTAG_MCP_TRST_N
  7  IO7  UNSPEC  = PWRGD_CPU0_G_R
  8  IO8  UNSPEC  = TP_JTAG_MCP_IO8_RSVD
  9  IO9  UNSPEC  = JTAG_MCP_MUX_TDI
  10  IO10  UNSPEC  = GND

J9G1  CONN12_C73564003  CONN  pkg PIP  page 137
  1  IO1  BI  = PU_UV_HIGH_SET
  2  IO2  BI  = TP_RST_RTCRST_N
  3  IO3  BI  = UV_HIGH_SET
  4  IO4  BI  = RST_RTCRST_N
  5  IO5  BI  = PD_UV_HIGH_SET
  6  IO6  BI  = PD_RST_RTCRST_N
  7  IO7  BI  = TP_IE_DEBUG_MODE
  8  IO8  BI  = PU_SPI_BMC_BT_CS0_N
  9  IO9  BI  = FM_UART_PRES_N
  10  IO10  BI  = SPI_BMC_BT_CS0_N
  11  IO11  BI  = PD_IE_DEBUG_MODE
  12  IO12  BI  = PD_SPI_BMC_BT_CS0_N
